(kicad_pcb
	(version 20260206)
	(generator "pcbnew")
	(generator_version "10.0")
	(general
		(thickness 1.6)
		(legacy_teardrops no)
	)
	(paper "A4")
	(title_block
		(title "Bryce Canyon_IOM_IOC_16318-2_OCP.brd")
		(comment 1 "Bryce Canyon / footprints 981-988 of 1605")
	)
	(layers
		(0 "F.Cu" signal "TOP")
		(4 "In1.Cu" signal "L2GND")
		(6 "In2.Cu" signal "L3")
		(8 "In3.Cu" signal "L4VCC")
		(10 "In4.Cu" signal "L5VCC")
		(12 "In5.Cu" signal "L6")
		(14 "In6.Cu" signal "L7GND")
		(2 "B.Cu" signal "BOTTOM")
		(9 "F.Adhes" user "F.Adhesive")
		(11 "B.Adhes" user "B.Adhesive")
		(13 "F.Paste" user "Package Geometry/Pastemask Top")
		(15 "B.Paste" user "Package Geometry/Pastemask Bottom")
		(5 "F.SilkS" user "Ref Des/Silkscreen Top")
		(7 "B.SilkS" user "Ref Des/Silkscreen Bottom")
		(1 "F.Mask" user "Board Geometry/Soldermask Top")
		(3 "B.Mask" user "Board Geometry/Soldermask Bottom")
		(17 "Dwgs.User" user "User.Drawings")
		(19 "Cmts.User" user "User.Comments")
		(21 "Eco1.User" user "User.Eco1")
		(23 "Eco2.User" user "User.Eco2")
		(25 "Edge.Cuts" user "Board Geometry/Outline")
		(27 "Margin" user)
		(31 "F.CrtYd" user "Package Geometry/Place Bound Top")
		(29 "B.CrtYd" user "Package Geometry/Place Bound Bottom")
		(35 "F.Fab" user "Ref Des/Assembly Top")
		(33 "B.Fab" user "Ref Des/Assembly Bottom")
	)
	(footprint ""
		(layer "B.Cu")
		(at 192.231518 -81.153 180)
		(property "Reference" "C299"
			(at 0 0 0)
			(layer "B.SilkS")
			(hide yes)
			(effects
				(font
					(size 1.27 1.27)
				)
				(justify mirror)
			)
		)
		(property "Value" "SCD22U10V1KX-GP"
			(at 2.8321 -1.7399 180)
			(unlocked yes)
			(layer "B.Fab")
			(hide yes)
			(effects
				(font
					(size 1.016 1.016)
					(thickness 0.1524)
				)
				(justify mirror)
			)
		)
		(property "Device Type" "C0201H13"
			(at 2.8321 -3.2639 180)
			(unlocked yes)
			(layer "B.Fab")
			(hide yes)
			(effects
				(font
					(size 1.016 1.016)
					(thickness 0.1524)
				)
				(justify mirror)
			)
		)
		(duplicate_pad_numbers_are_jumpers no)
		(fp_rect
			(start 0.2794 0.6477)
			(end -0.2794 -0.6477)
			(stroke
				(width 0)
				(type default)
			)
			(fill no)
			(layer "B.CrtYd")
		)
		(fp_rect
			(start 0.2794 0.6477)
			(end -0.2794 -0.6477)
			(stroke
				(width 0)
				(type default)
			)
			(fill no)
			(layer "B.Fab")
		)
		(pad "1" smd custom
			(at 0 -0.2794)
			(size 0.0762 0.0762)
			(layers "B.Cu" "B.Mask" "B.Paste")
			(net "PCIE_IOM_TO_COMP_13_DP_C")
			(options
				(clearance outline)
				(anchor circle)
			)
			(primitives
				(gr_poly
					(pts
						(arc
							(start 0.1524 0.127)
							(mid 0.137521 0.162921)
							(end 0.1016 0.1778)
						)
						(arc
							(start -0.1016 0.1778)
							(mid -0.137521 0.162921)
							(end -0.1524 0.127)
						)
						(arc
							(start -0.1524 -0.127)
							(mid -0.137521 -0.162921)
							(end -0.1016 -0.1778)
						)
						(arc
							(start 0.1016 -0.1778)
							(mid 0.137521 -0.162921)
							(end 0.1524 -0.127)
						)
					)
					(width 0)
					(fill yes)
				)
			)
		)
		(pad "2" smd custom
			(at 0 0.2794)
			(size 0.0762 0.0762)
			(layers "B.Cu" "B.Mask" "B.Paste")
			(net "PCIE_IOM_TO_COMP_13_DP")
			(options
				(clearance outline)
				(anchor circle)
			)
			(primitives
				(gr_poly
					(pts
						(arc
							(start 0.1524 0.127)
							(mid 0.137521 0.162921)
							(end 0.1016 0.1778)
						)
						(arc
							(start -0.1016 0.1778)
							(mid -0.137521 0.162921)
							(end -0.1524 0.127)
						)
						(arc
							(start -0.1524 -0.127)
							(mid -0.137521 -0.162921)
							(end -0.1016 -0.1778)
						)
						(arc
							(start 0.1016 -0.1778)
							(mid 0.137521 -0.162921)
							(end 0.1524 -0.127)
						)
					)
					(width 0)
					(fill yes)
				)
			)
		)
	)
	(footprint ""
		(layer "B.Cu")
		(at 213.2076 -122.301 90)
		(property "Reference" "C247"
			(at 0 0 90)
			(layer "B.SilkS")
			(hide yes)
			(effects
				(font
					(size 1.27 1.27)
				)
				(justify mirror)
			)
		)
		(property "Value" "SC10U6D3V5KX-4GP"
			(at 0.0762 -6.1214 90)
			(unlocked yes)
			(layer "B.Fab")
			(hide yes)
			(effects
				(font
					(size 1.016 1.016)
					(thickness 0.1524)
				)
				(justify mirror)
			)
		)
		(property "Device Type" "C805H58"
			(at 0.0762 -8.1534 90)
			(unlocked yes)
			(layer "B.Fab")
			(hide yes)
			(effects
				(font
					(size 1.016 1.016)
					(thickness 0.1524)
				)
				(justify mirror)
			)
		)
		(duplicate_pad_numbers_are_jumpers no)
		(fp_line
			(start -0.635 0)
			(end 0.635 0)
			(stroke
				(width 0.508)
				(type default)
			)
			(layer "B.SilkS")
		)
		(fp_rect
			(start 0.9652 1.778)
			(end -0.9652 -1.778)
			(stroke
				(width 0)
				(type default)
			)
			(fill no)
			(layer "B.CrtYd")
		)
		(fp_poly
			(pts
				(xy 0.9652 -1.778) (xy -0.9652 -1.778) (xy -0.9652 1.778) (xy 0.9652 1.778)
			)
			(stroke
				(width 0)
				(type default)
			)
			(fill no)
			(layer "B.Fab")
		)
		(pad "1" smd rect
			(at 0 -0.9652 270)
			(size 1.397 1.143)
			(layers "B.Cu" "B.Mask" "B.Paste")
			(net "P1V5_OUT")
		)
		(pad "2" smd rect
			(at 0 0.9652 270)
			(size 1.397 1.143)
			(layers "B.Cu" "B.Mask" "B.Paste")
			(net "GND")
		)
	)
	(footprint ""
		(layer "B.Cu")
		(at 127.104394 -13.60551)
		(property "Reference" "R447"
			(at 0 0 0)
			(layer "B.SilkS")
			(hide yes)
			(effects
				(font
					(size 1.27 1.27)
				)
				(justify mirror)
			)
		)
		(property "Value" "4K12R2F-3-GP"
			(at -0.064008 -3.993896 0)
			(unlocked yes)
			(layer "B.Fab")
			(hide yes)
			(effects
				(font
					(size 1.016 1.016)
					(thickness 0.1524)
				)
				(justify mirror)
			)
		)
		(property "Device Type" "R402H16"
			(at -0.064008 -5.517896 0)
			(unlocked yes)
			(layer "B.Fab")
			(hide yes)
			(effects
				(font
					(size 1.016 1.016)
					(thickness 0.1524)
				)
				(justify mirror)
			)
		)
		(duplicate_pad_numbers_are_jumpers no)
		(fp_line
			(start -0.508 -0.9398)
			(end 0.508 -0.9398)
			(stroke
				(width 0.1524)
				(type default)
			)
			(layer "B.SilkS")
		)
		(fp_line
			(start 0.508 -0.9398)
			(end 0.508 0.9398)
			(stroke
				(width 0.1524)
				(type default)
			)
			(layer "B.SilkS")
		)
		(fp_rect
			(start 0.508 0.9398)
			(end -0.508 -0.9398)
			(stroke
				(width 0)
				(type default)
			)
			(fill no)
			(layer "B.CrtYd")
		)
		(fp_rect
			(start 0.508 0.9398)
			(end -0.508 -0.9398)
			(stroke
				(width 0)
				(type default)
			)
			(fill no)
			(layer "B.Fab")
		)
		(pad "1" smd custom
			(at 0 -0.4445 180)
			(size 0.1397 0.1397)
			(layers "B.Cu" "B.Mask" "B.Paste")
			(net "MB0_CM_OV_R")
			(options
				(clearance outline)
				(anchor circle)
			)
			(primitives
				(gr_poly
					(pts
						(arc
							(start -0.1778 0.2794)
							(mid -0.249642 0.249642)
							(end -0.2794 0.1778)
						)
						(arc
							(start -0.2794 -0.1778)
							(mid -0.249642 -0.249642)
							(end -0.1778 -0.2794)
						)
						(arc
							(start 0.1778 -0.2794)
							(mid 0.249642 -0.249642)
							(end 0.2794 -0.1778)
						)
						(arc
							(start 0.2794 0.1778)
							(mid 0.249642 0.249642)
							(end 0.1778 0.2794)
						)
					)
					(width 0)
					(fill yes)
				)
			)
		)
		(pad "2" smd custom
			(at 0 0.4445 180)
			(size 0.1397 0.1397)
			(layers "B.Cu" "B.Mask" "B.Paste")
			(net "AGND_CURRENT_MON")
			(options
				(clearance outline)
				(anchor circle)
			)
			(primitives
				(gr_poly
					(pts
						(arc
							(start -0.1778 0.2794)
							(mid -0.249642 0.249642)
							(end -0.2794 0.1778)
						)
						(arc
							(start -0.2794 -0.1778)
							(mid -0.249642 -0.249642)
							(end -0.1778 -0.2794)
						)
						(arc
							(start 0.1778 -0.2794)
							(mid 0.249642 -0.249642)
							(end 0.2794 -0.1778)
						)
						(arc
							(start 0.2794 0.1778)
							(mid 0.249642 0.249642)
							(end 0.1778 0.2794)
						)
					)
					(width 0)
					(fill yes)
				)
			)
		)
	)
	(footprint ""
		(layer "B.Cu")
		(at 14.4272 -146.2659 90)
		(property "Reference" "R210"
			(at 0 0 90)
			(layer "B.SilkS")
			(hide yes)
			(effects
				(font
					(size 1.27 1.27)
				)
				(justify mirror)
			)
		)
		(property "Value" "120R2F-GP"
			(at -0.064008 -3.993896 90)
			(unlocked yes)
			(layer "B.Fab")
			(hide yes)
			(effects
				(font
					(size 1.016 1.016)
					(thickness 0.1524)
				)
				(justify mirror)
			)
		)
		(property "Device Type" "R402H16"
			(at -0.064008 -5.517896 90)
			(unlocked yes)
			(layer "B.Fab")
			(hide yes)
			(effects
				(font
					(size 1.016 1.016)
					(thickness 0.1524)
				)
				(justify mirror)
			)
		)
		(duplicate_pad_numbers_are_jumpers no)
		(fp_line
			(start 0.508 -0.9398)
			(end 0.508 0.9398)
			(stroke
				(width 0.1524)
				(type default)
			)
			(layer "B.SilkS")
		)
		(fp_line
			(start -0.508 -0.9398)
			(end 0.508 -0.9398)
			(stroke
				(width 0.1524)
				(type default)
			)
			(layer "B.SilkS")
		)
		(fp_rect
			(start 0.508 0.9398)
			(end -0.508 -0.9398)
			(stroke
				(width 0)
				(type default)
			)
			(fill no)
			(layer "B.CrtYd")
		)
		(fp_rect
			(start 0.508 0.9398)
			(end -0.508 -0.9398)
			(stroke
				(width 0)
				(type default)
			)
			(fill no)
			(layer "B.Fab")
		)
		(pad "1" smd custom
			(at 0 -0.4445 270)
			(size 0.1397 0.1397)
			(layers "B.Cu" "B.Mask" "B.Paste")
			(net "MEMCKE")
			(options
				(clearance outline)
				(anchor circle)
			)
			(primitives
				(gr_poly
					(pts
						(arc
							(start -0.1778 0.2794)
							(mid -0.249642 0.249642)
							(end -0.2794 0.1778)
						)
						(arc
							(start -0.2794 -0.1778)
							(mid -0.249642 -0.249642)
							(end -0.1778 -0.2794)
						)
						(arc
							(start 0.1778 -0.2794)
							(mid 0.249642 -0.249642)
							(end 0.2794 -0.1778)
						)
						(arc
							(start 0.2794 0.1778)
							(mid 0.249642 0.249642)
							(end 0.1778 0.2794)
						)
					)
					(width 0)
					(fill yes)
				)
			)
		)
		(pad "2" smd custom
			(at 0 0.4445 270)
			(size 0.1397 0.1397)
			(layers "B.Cu" "B.Mask" "B.Paste")
			(net "P1V2_STBY")
			(options
				(clearance outline)
				(anchor circle)
			)
			(primitives
				(gr_poly
					(pts
						(arc
							(start -0.1778 0.2794)
							(mid -0.249642 0.249642)
							(end -0.2794 0.1778)
						)
						(arc
							(start -0.2794 -0.1778)
							(mid -0.249642 -0.249642)
							(end -0.1778 -0.2794)
						)
						(arc
							(start 0.1778 -0.2794)
							(mid 0.249642 -0.249642)
							(end 0.2794 -0.1778)
						)
						(arc
							(start 0.2794 0.1778)
							(mid 0.249642 0.249642)
							(end 0.1778 0.2794)
						)
					)
					(width 0)
					(fill yes)
				)
			)
		)
	)
	(footprint ""
		(layer "B.Cu")
		(at 93.98 -175.133 90)
		(property "Reference" "C37"
			(at 0 0 90)
			(layer "B.SilkS")
			(hide yes)
			(effects
				(font
					(size 1.27 1.27)
				)
				(justify mirror)
			)
		)
		(property "Value" "SCD1U16V2KX-3GP"
			(at -1.1811 -2.7051 90)
			(unlocked yes)
			(layer "B.Fab")
			(hide yes)
			(effects
				(font
					(size 1.016 1.016)
					(thickness 0.1524)
				)
				(justify mirror)
			)
		)
		(property "Device Type" "C402H22"
			(at -1.1811 -4.2291 90)
			(unlocked yes)
			(layer "B.Fab")
			(hide yes)
			(effects
				(font
					(size 1.016 1.016)
					(thickness 0.1524)
				)
				(justify mirror)
			)
		)
		(duplicate_pad_numbers_are_jumpers no)
		(fp_rect
			(start 0.4318 0.9525)
			(end -0.4318 -0.9525)
			(stroke
				(width 0)
				(type default)
			)
			(fill no)
			(layer "B.CrtYd")
		)
		(fp_rect
			(start 0.4318 0.9525)
			(end -0.4318 -0.9525)
			(stroke
				(width 0)
				(type default)
			)
			(fill no)
			(layer "B.Fab")
		)
		(pad "1" smd custom
			(at 0 -0.4445 270)
			(size 0.1524 0.1524)
			(layers "B.Cu" "B.Mask" "B.Paste")
			(net "P3V3_STBY")
			(options
				(clearance outline)
				(anchor circle)
			)
			(primitives
				(gr_poly
					(pts
						(arc
							(start 0.3048 0.2032)
							(mid 0.275042 0.275042)
							(end 0.2032 0.3048)
						)
						(arc
							(start -0.2032 0.3048)
							(mid -0.275042 0.275042)
							(end -0.3048 0.2032)
						)
						(arc
							(start -0.3048 -0.2032)
							(mid -0.275042 -0.275042)
							(end -0.2032 -0.3048)
						)
						(arc
							(start 0.2032 -0.3048)
							(mid 0.275042 -0.275042)
							(end 0.3048 -0.2032)
						)
					)
					(width 0)
					(fill yes)
				)
			)
		)
		(pad "2" smd custom
			(at 0 0.4445 270)
			(size 0.1524 0.1524)
			(layers "B.Cu" "B.Mask" "B.Paste")
			(net "GND")
			(options
				(clearance outline)
				(anchor circle)
			)
			(primitives
				(gr_poly
					(pts
						(arc
							(start 0.3048 0.2032)
							(mid 0.275042 0.275042)
							(end 0.2032 0.3048)
						)
						(arc
							(start -0.2032 0.3048)
							(mid -0.275042 0.275042)
							(end -0.3048 0.2032)
						)
						(arc
							(start -0.3048 -0.2032)
							(mid -0.275042 -0.275042)
							(end -0.2032 -0.3048)
						)
						(arc
							(start 0.2032 -0.3048)
							(mid 0.275042 -0.275042)
							(end 0.3048 -0.2032)
						)
					)
					(width 0)
					(fill yes)
				)
			)
		)
	)
	(footprint ""
		(layer "B.Cu")
		(at 12.091924 -133.85673 90)
		(property "Reference" "R243"
			(at 0 0 90)
			(layer "B.SilkS")
			(hide yes)
			(effects
				(font
					(size 1.27 1.27)
				)
				(justify mirror)
			)
		)
		(property "Value" "120R2F-GP"
			(at -0.064008 -3.993896 90)
			(unlocked yes)
			(layer "B.Fab")
			(hide yes)
			(effects
				(font
					(size 1.016 1.016)
					(thickness 0.1524)
				)
				(justify mirror)
			)
		)
		(property "Device Type" "R402H16"
			(at -0.064008 -5.517896 90)
			(unlocked yes)
			(layer "B.Fab")
			(hide yes)
			(effects
				(font
					(size 1.016 1.016)
					(thickness 0.1524)
				)
				(justify mirror)
			)
		)
		(duplicate_pad_numbers_are_jumpers no)
		(fp_line
			(start 0.508 -0.9398)
			(end 0.508 0.9398)
			(stroke
				(width 0.1524)
				(type default)
			)
			(layer "B.SilkS")
		)
		(fp_line
			(start -0.508 -0.9398)
			(end 0.508 -0.9398)
			(stroke
				(width 0.1524)
				(type default)
			)
			(layer "B.SilkS")
		)
		(fp_rect
			(start 0.508 0.9398)
			(end -0.508 -0.9398)
			(stroke
				(width 0)
				(type default)
			)
			(fill no)
			(layer "B.CrtYd")
		)
		(fp_rect
			(start 0.508 0.9398)
			(end -0.508 -0.9398)
			(stroke
				(width 0)
				(type default)
			)
			(fill no)
			(layer "B.Fab")
		)
		(pad "1" smd custom
			(at 0 -0.4445 270)
			(size 0.1397 0.1397)
			(layers "B.Cu" "B.Mask" "B.Paste")
			(net "MEMA_4")
			(options
				(clearance outline)
				(anchor circle)
			)
			(primitives
				(gr_poly
					(pts
						(arc
							(start -0.1778 0.2794)
							(mid -0.249642 0.249642)
							(end -0.2794 0.1778)
						)
						(arc
							(start -0.2794 -0.1778)
							(mid -0.249642 -0.249642)
							(end -0.1778 -0.2794)
						)
						(arc
							(start 0.1778 -0.2794)
							(mid 0.249642 -0.249642)
							(end 0.2794 -0.1778)
						)
						(arc
							(start 0.2794 0.1778)
							(mid 0.249642 0.249642)
							(end 0.1778 0.2794)
						)
					)
					(width 0)
					(fill yes)
				)
			)
		)
		(pad "2" smd custom
			(at 0 0.4445 270)
			(size 0.1397 0.1397)
			(layers "B.Cu" "B.Mask" "B.Paste")
			(net "P1V2_STBY")
			(options
				(clearance outline)
				(anchor circle)
			)
			(primitives
				(gr_poly
					(pts
						(arc
							(start -0.1778 0.2794)
							(mid -0.249642 0.249642)
							(end -0.2794 0.1778)
						)
						(arc
							(start -0.2794 -0.1778)
							(mid -0.249642 -0.249642)
							(end -0.1778 -0.2794)
						)
						(arc
							(start 0.1778 -0.2794)
							(mid 0.249642 -0.249642)
							(end 0.2794 -0.1778)
						)
						(arc
							(start 0.2794 0.1778)
							(mid 0.249642 0.249642)
							(end 0.1778 0.2794)
						)
					)
					(width 0)
					(fill yes)
				)
			)
		)
	)
	(footprint ""
		(layer "B.Cu")
		(at 115.7478 -8.5344 90)
		(property "Reference" "R436"
			(at 0 0 90)
			(layer "B.SilkS")
			(hide yes)
			(effects
				(font
					(size 1.27 1.27)
				)
				(justify mirror)
			)
		)
		(property "Value" "0R2J-2-GP"
			(at -0.064008 -3.993896 90)
			(unlocked yes)
			(layer "B.Fab")
			(hide yes)
			(effects
				(font
					(size 1.016 1.016)
					(thickness 0.1524)
				)
				(justify mirror)
			)
		)
		(property "Device Type" "R402H16"
			(at -0.064008 -5.517896 90)
			(unlocked yes)
			(layer "B.Fab")
			(hide yes)
			(effects
				(font
					(size 1.016 1.016)
					(thickness 0.1524)
				)
				(justify mirror)
			)
		)
		(duplicate_pad_numbers_are_jumpers no)
		(fp_line
			(start 0.508 -0.9398)
			(end 0.508 0.9398)
			(stroke
				(width 0.1524)
				(type default)
			)
			(layer "B.SilkS")
		)
		(fp_line
			(start -0.508 -0.9398)
			(end 0.508 -0.9398)
			(stroke
				(width 0.1524)
				(type default)
			)
			(layer "B.SilkS")
		)
		(fp_rect
			(start 0.508 0.9398)
			(end -0.508 -0.9398)
			(stroke
				(width 0)
				(type default)
			)
			(fill no)
			(layer "B.CrtYd")
		)
		(fp_rect
			(start 0.508 0.9398)
			(end -0.508 -0.9398)
			(stroke
				(width 0)
				(type default)
			)
			(fill no)
			(layer "B.Fab")
		)
		(pad "1" smd custom
			(at 0 -0.4445 270)
			(size 0.1397 0.1397)
			(layers "B.Cu" "B.Mask" "B.Paste")
			(net "P12V_A_PGOOD")
			(options
				(clearance outline)
				(anchor circle)
			)
			(primitives
				(gr_poly
					(pts
						(arc
							(start -0.1778 0.2794)
							(mid -0.249642 0.249642)
							(end -0.2794 0.1778)
						)
						(arc
							(start -0.2794 -0.1778)
							(mid -0.249642 -0.249642)
							(end -0.1778 -0.2794)
						)
						(arc
							(start 0.1778 -0.2794)
							(mid 0.249642 -0.249642)
							(end 0.2794 -0.1778)
						)
						(arc
							(start 0.2794 0.1778)
							(mid 0.249642 0.249642)
							(end 0.1778 0.2794)
						)
					)
					(width 0)
					(fill yes)
				)
			)
		)
		(pad "2" smd custom
			(at 0 0.4445 270)
			(size 0.1397 0.1397)
			(layers "B.Cu" "B.Mask" "B.Paste")
			(net "MB0_HS_ENABLE")
			(options
				(clearance outline)
				(anchor circle)
			)
			(primitives
				(gr_poly
					(pts
						(arc
							(start -0.1778 0.2794)
							(mid -0.249642 0.249642)
							(end -0.2794 0.1778)
						)
						(arc
							(start -0.2794 -0.1778)
							(mid -0.249642 -0.249642)
							(end -0.1778 -0.2794)
						)
						(arc
							(start 0.1778 -0.2794)
							(mid 0.249642 -0.249642)
							(end 0.2794 -0.1778)
						)
						(arc
							(start 0.2794 0.1778)
							(mid 0.249642 0.249642)
							(end 0.1778 0.2794)
						)
					)
					(width 0)
					(fill yes)
				)
			)
		)
	)
	(footprint ""
		(layer "B.Cu")
		(at 46.3296 -142.0368 90)
		(property "Reference" "C100"
			(at 0 0 90)
			(layer "B.SilkS")
			(hide yes)
			(effects
				(font
					(size 1.27 1.27)
				)
				(justify mirror)
			)
		)
		(property "Value" "SC1U16V3KX-5GP"
			(at 0 -2.8194 90)
			(unlocked yes)
			(layer "B.Fab")
			(hide yes)
			(effects
				(font
					(size 1.016 1.016)
					(thickness 0.1524)
				)
				(justify mirror)
			)
		)
		(property "Device Type" "C603H36"
			(at 0 -4.3434 90)
			(unlocked yes)
			(layer "B.Fab")
			(hide yes)
			(effects
				(font
					(size 1.016 1.016)
					(thickness 0.1524)
				)
				(justify mirror)
			)
		)
		(duplicate_pad_numbers_are_jumpers no)
		(fp_line
			(start -0.508 0)
			(end 0.508 0)
			(stroke
				(width 0.2032)
				(type default)
			)
			(layer "B.SilkS")
		)
		(fp_rect
			(start 0.5842 1.3335)
			(end -0.5842 -1.3335)
			(stroke
				(width 0)
				(type default)
			)
			(fill no)
			(layer "B.CrtYd")
		)
		(fp_rect
			(start 0.5842 1.3335)
			(end -0.5842 -1.3335)
			(stroke
				(width 0)
				(type default)
			)
			(fill no)
			(layer "B.Fab")
		)
		(pad "1" smd custom
			(at 0 -0.762 270)
			(size 0.2159 0.2159)
			(layers "B.Cu" "B.Mask" "B.Paste")
			(net "P3V3_STBY")
			(options
				(clearance outline)
				(anchor circle)
			)
			(primitives
				(gr_poly
					(pts
						(arc
							(start -0.3302 0.4318)
							(mid -0.402042 0.402042)
							(end -0.4318 0.3302)
						)
						(arc
							(start -0.4318 -0.3302)
							(mid -0.402042 -0.402042)
							(end -0.3302 -0.4318)
						)
						(arc
							(start 0.3302 -0.4318)
							(mid 0.402042 -0.402042)
							(end 0.4318 -0.3302)
						)
						(arc
							(start 0.4318 0.3302)
							(mid 0.402042 0.402042)
							(end 0.3302 0.4318)
						)
					)
					(width 0)
					(fill yes)
				)
			)
		)
		(pad "2" smd custom
			(at 0 0.762 270)
			(size 0.2159 0.2159)
			(layers "B.Cu" "B.Mask" "B.Paste")
			(net "GND")
			(options
				(clearance outline)
				(anchor circle)
			)
			(primitives
				(gr_poly
					(pts
						(arc
							(start -0.3302 0.4318)
							(mid -0.402042 0.402042)
							(end -0.4318 0.3302)
						)
						(arc
							(start -0.4318 -0.3302)
							(mid -0.402042 -0.402042)
							(end -0.3302 -0.4318)
						)
						(arc
							(start 0.3302 -0.4318)
							(mid 0.402042 -0.402042)
							(end 0.4318 -0.3302)
						)
						(arc
							(start 0.4318 0.3302)
							(mid 0.402042 0.402042)
							(end 0.3302 0.4318)
						)
					)
					(width 0)
					(fill yes)
				)
			)
		)
	)
)
